FILE_TYPE = CONNECTIVITY;
{Allegro Design Entry HDL 17.4-2019 S026 (4007227) 1/17/2022}
"PAGE_NUMBER" = 382;
0"NC";
1"P5E_CPU0_P0_RX_DP<15:8>";
2"P5E_CPU0_P0_RX_DP<7:0>";
3"P5E_CPU0_P0_RX_DN<15:8>";
4"P5E_CPU0_P0_RX_DN<7:0>";
5"P5E_CPU0_P0_RX_DP<15>";
6"P5E_CPU0_P0_RX_DN<15>";
7"P5E_CPU0_P0_RX_DN<14>";
8"P5E_CPU0_P0_RX_DP<14>";
9"P5E_CPU0_P0_RX_DN<3>";
10"P5E_CPU0_P0_RX_DP<5>";
11"P5E_CPU0_P0_RX_DN<6>";
12"P5E_CPU0_P0_RX_DP<6>";
13"P5E_CPU0_P0_RX_DN<7>";
14"P5E_CPU0_P0_RX_DP<7>";
15"P5E_CPU0_P0_RX_DN<5>";
16"P5E_CPU0_P0_RX_DN<4>";
17"P5E_CPU0_P0_RX_DP<3>";
18"P5E_CPU0_P0_RX_DP<2>";
19"P5E_CPU0_P0_RX_DN<2>";
20"P5E_CPU0_P0_RX_DP<1>";
21"P5E_CPU0_P0_RX_DN<1>";
22"P5E_CPU0_P0_RX_DN<13>";
23"P5E_CPU0_P0_RX_DN<0>";
24"P5E_CPU0_P0_RX_DN<8>";
25"P5E_CPU0_P0_RX_DN<10>";
26"P5E_CPU0_P0_RX_DN<9>";
27"P5E_CPU0_P0_RX_DN<11>";
28"P5E_CPU0_P0_RX_DN<12>";
29"P5E_CPU0_P0_RX_DP<0>";
30"P5E_CPU0_P0_RX_DP<13>";
31"P5E_CPU0_P0_RX_DP<4>";
32"P5E_CPU0_P0_RX_DP<8>";
33"P5E_CPU0_P0_RX_DP<9>";
34"P5E_CPU0_P0_RX_DP<10>";
35"P5E_CPU0_P0_RX_DP<11>";
36"P5E_CPU0_P0_RX_DP<12>";
%"TAP"
"1","(-6825,4575)","0","standard","I10";
;
CDS_LIB"standard"
BODY_TYPE"PLUMBING"
HDL_TAP"TRUE";
"B \NAC \NWC"1;
"S \NAC"
BN"12"36;
%"TAP"
"1","(-6625,4475)","0","standard","I11";
;
CDS_LIB"standard"
BODY_TYPE"PLUMBING"
HDL_TAP"TRUE";
"B \NAC \NWC"3;
"S \NAC"
BN"12"28;
%"TAP"
"1","(-6825,4925)","0","standard","I12";
;
CDS_LIB"standard"
BODY_TYPE"PLUMBING"
HDL_TAP"TRUE";
"B \NAC \NWC"1;
"S \NAC"
BN"13"30;
%"TAP"
"1","(-6625,4825)","0","standard","I13";
;
CDS_LIB"standard"
BODY_TYPE"PLUMBING"
HDL_TAP"TRUE";
"B \NAC \NWC"3;
"S \NAC"
BN"13"22;
%"TAP"
"1","(-6625,5175)","0","standard","I14";
;
CDS_LIB"standard"
BODY_TYPE"PLUMBING"
HDL_TAP"TRUE";
"B \NAC \NWC"3;
"S \NAC"
BN"14"7;
%"TAP"
"1","(-6825,5275)","0","standard","I15";
;
CDS_LIB"standard"
BODY_TYPE"PLUMBING"
HDL_TAP"TRUE";
"B \NAC \NWC"1;
"S \NAC"
BN"14"8;
%"TAP"
"1","(-6825,5625)","0","standard","I16";
;
CDS_LIB"standard"
BODY_TYPE"PLUMBING"
HDL_TAP"TRUE";
"B \NAC \NWC"1;
"S \NAC"
BN"15"5;
%"TAP"
"1","(-6625,5525)","0","standard","I17";
;
CDS_LIB"standard"
BODY_TYPE"PLUMBING"
HDL_TAP"TRUE";
"B \NAC \NWC"3;
"S \NAC"
BN"15"6;
%"PT5161LRS"
"6","(-7850,4375)","0","pure_quanta","I2";
;
LOCATION"U6010"
$SEC"6"
CDS_SEC"6"
MATERIAL"IC"
VALUE"PT5161LRS"
PART_TYPE"SMLF"
NEEDS_NO_SIZE"TRUE"
CDS_LMAN_SYM_OUTLINE"-350,1450,300,-1400"
CDS_LIB"pure_quanta"
PART_NUMBER"AJ051610U03";
"A_PETN7"
$PN"CC29"24;
"A_PETP7"
$PN"CA26"32;
"A_PETN6"
$PN"BT29"26;
"A_PETP6"
$PN"BP26"33;
"A_PETN5"
$PN"BJ29"25;
"A_PETP5"
$PN"BG26"34;
"A_PETN4"
$PN"BB29"27;
"A_PETP4"
$PN"AY26"35;
"A_PETN3"
$PN"AR29"28;
"A_PETP3"
$PN"AN26"36;
"A_PETN2"
$PN"AH29"22;
"A_PETP2"
$PN"AF26"30;
"A_PETN1"
$PN"AA29"7;
"A_PETP1"
$PN"W26"8;
"A_PETN0"
$PN"P29"6;
"A_PETP0"
$PN"M26"5;
%"TAP"
"1","(-6825,3175)","0","standard","I20";
;
CDS_LIB"standard"
BODY_TYPE"PLUMBING"
HDL_TAP"TRUE";
"B \NAC \NWC"1;
"S \NAC"
BN"8"32;
%"TAP"
"1","(-6625,3425)","0","standard","I21";
;
CDS_LIB"standard"
BODY_TYPE"PLUMBING"
HDL_TAP"TRUE";
"B \NAC \NWC"3;
"S \NAC"
BN"9"26;
%"TAP"
"1","(-2450,3200)","0","standard","I24";
;
CDS_LIB"standard"
BODY_TYPE"PLUMBING"
HDL_TAP"TRUE";
"B \NAC \NWC"2;
"S \NAC"
BN"0"29;
%"TAP"
"1","(-2250,3100)","0","standard","I25";
;
CDS_LIB"standard"
BODY_TYPE"PLUMBING"
HDL_TAP"TRUE";
"B \NAC \NWC"4;
"S \NAC"
BN"0"23;
%"TAP"
"1","(-2450,3550)","0","standard","I26";
;
CDS_LIB"standard"
BODY_TYPE"PLUMBING"
HDL_TAP"TRUE";
"B \NAC \NWC"2;
"S \NAC"
BN"1"20;
%"TAP"
"1","(-2250,3450)","0","standard","I27";
;
CDS_LIB"standard"
BODY_TYPE"PLUMBING"
HDL_TAP"TRUE";
"B \NAC \NWC"4;
"S \NAC"
BN"1"21;
%"TAP"
"1","(-2450,3900)","0","standard","I28";
;
CDS_LIB"standard"
BODY_TYPE"PLUMBING"
HDL_TAP"TRUE";
"B \NAC \NWC"2;
"S \NAC"
BN"2"18;
%"TAP"
"1","(-2450,4250)","0","standard","I29";
;
CDS_LIB"standard"
BODY_TYPE"PLUMBING"
HDL_TAP"TRUE";
"B \NAC \NWC"2;
"S \NAC"
BN"3"17;
%"PT5161LRS"
"7","(-3475,4400)","0","pure_quanta","I3";
;
LOCATION"U6010"
$SEC"7"
CDS_SEC"7"
MATERIAL"IC"
PART_TYPE"SMLF"
VALUE"PT5161LRS"
CDS_LIB"pure_quanta"
CDS_LMAN_SYM_OUTLINE"-350,1450,300,-1400"
NEEDS_NO_SIZE"TRUE"
PART_NUMBER"AJ051610U03";
"A_PETN15"
$PN"EW29"23;
"A_PETP15"
$PN"EU26"29;
"A_PETN14"
$PN"EM29"21;
"A_PETP14"
$PN"EK26"20;
"A_PETN13"
$PN"EE29"19;
"A_PETP13"
$PN"EC26"18;
"A_PETN12"
$PN"DV29"9;
"A_PETP12"
$PN"DT26"17;
"A_PETN11"
$PN"DL29"16;
"A_PETP11"
$PN"DJ26"31;
"A_PETN10"
$PN"DD29"15;
"A_PETP10"
$PN"DB26"10;
"A_PETN9"
$PN"CU29"11;
"A_PETP9"
$PN"CR26"12;
"A_PETN8"
$PN"CK29"13;
"A_PETP8"
$PN"CH26"14;
%"TAP"
"1","(-2250,3800)","0","standard","I30";
;
CDS_LIB"standard"
BODY_TYPE"PLUMBING"
HDL_TAP"TRUE";
"B \NAC \NWC"4;
"S \NAC"
BN"2"19;
%"TAP"
"1","(-2250,4150)","0","standard","I31";
;
CDS_LIB"standard"
BODY_TYPE"PLUMBING"
HDL_TAP"TRUE";
"B \NAC \NWC"4;
"S \NAC"
BN"3"9;
%"TAP"
"1","(-2450,4600)","0","standard","I32";
;
CDS_LIB"standard"
BODY_TYPE"PLUMBING"
HDL_TAP"TRUE";
"B \NAC \NWC"2;
"S \NAC"
BN"4"31;
%"TAP"
"1","(-2250,4500)","0","standard","I33";
;
CDS_LIB"standard"
BODY_TYPE"PLUMBING"
HDL_TAP"TRUE";
"B \NAC \NWC"4;
"S \NAC"
BN"4"16;
%"TAP"
"1","(-2450,4950)","0","standard","I34";
;
CDS_LIB"standard"
BODY_TYPE"PLUMBING"
HDL_TAP"TRUE";
"B \NAC \NWC"2;
"S \NAC"
BN"5"10;
%"TAP"
"1","(-2250,4850)","0","standard","I35";
;
CDS_LIB"standard"
BODY_TYPE"PLUMBING"
HDL_TAP"TRUE";
"B \NAC \NWC"4;
"S \NAC"
BN"5"15;
%"TAP"
"1","(-2250,5200)","0","standard","I36";
;
CDS_LIB"standard"
BODY_TYPE"PLUMBING"
HDL_TAP"TRUE";
"B \NAC \NWC"4;
"S \NAC"
BN"6"11;
%"TAP"
"1","(-2450,5300)","0","standard","I37";
;
CDS_LIB"standard"
BODY_TYPE"PLUMBING"
HDL_TAP"TRUE";
"B \NAC \NWC"2;
"S \NAC"
BN"6"12;
%"TAP"
"1","(-2450,5650)","0","standard","I38";
;
CDS_LIB"standard"
BODY_TYPE"PLUMBING"
HDL_TAP"TRUE";
"B \NAC \NWC"2;
"S \NAC"
BN"7"14;
%"TAP"
"1","(-2250,5550)","0","standard","I39";
;
CDS_LIB"standard"
BODY_TYPE"PLUMBING"
HDL_TAP"TRUE";
"B \NAC \NWC"4;
"S \NAC"
BN"7"13;
%"TAP"
"1","(-6625,3075)","0","standard","I4";
;
CDS_LIB"standard"
BODY_TYPE"PLUMBING"
HDL_TAP"TRUE";
"B \NAC \NWC"3;
"S \NAC"
BN"8"24;
%"TAP"
"1","(-6825,3525)","0","standard","I5";
;
CDS_LIB"standard"
BODY_TYPE"PLUMBING"
HDL_TAP"TRUE";
"B \NAC \NWC"1;
"S \NAC"
BN"9"33;
%"TAP"
"1","(-6825,3875)","0","standard","I6";
;
CDS_LIB"standard"
BODY_TYPE"PLUMBING"
HDL_TAP"TRUE";
"B \NAC \NWC"1;
"S \NAC"
BN"10"34;
%"TAP"
"1","(-6625,3775)","0","standard","I7";
;
CDS_LIB"standard"
BODY_TYPE"PLUMBING"
HDL_TAP"TRUE";
"B \NAC \NWC"3;
"S \NAC"
BN"10"25;
%"TAP"
"1","(-6625,4125)","0","standard","I8";
;
CDS_LIB"standard"
BODY_TYPE"PLUMBING"
HDL_TAP"TRUE";
"B \NAC \NWC"3;
"S \NAC"
BN"11"27;
%"TAP"
"1","(-6825,4225)","0","standard","I9";
;
CDS_LIB"standard"
BODY_TYPE"PLUMBING"
HDL_TAP"TRUE";
"B \NAC \NWC"1;
"S \NAC"
BN"11"35;
END.
